# T6G (Grand Teton) — schematic netlist excerpt (pin names and nets, part order shuffled) for the footprints in the layout excerpt that follows; sources: Cadence DE-HDL packaged netlist, KiCad conversion of 04192023_DAF0TMB3IC0_F0TG_MB_C_brd_V02_OCP.brd

X8012  TP_TDR_4P_FTS  TP_TDR_4P_DIP EMPTY  pkg TH  page 260
  S1  = TDR_DIFF_85_BOT_DN
  P1  = T1_GND
  P2  = T1_GND
  S2  = TDR_DIFF_85_BOT_DP

(kicad_pcb
	(version 20260206)
	(generator "pcbnew")
	(generator_version "10.0")
	(general
		(thickness 1.6)
		(legacy_teardrops no)
	)
	(paper "A4")
	(title_block
		(title "04192023_DAF0TMB3IC0_F0TG_MB_C_brd_V02_OCP.brd")
		(comment 1 "Grand Teton / footprints 6186-6186 of 8354")
	)
	(layers
		(0 "F.Cu" signal "TOP")
		(4 "In1.Cu" signal "GND")
		(6 "In2.Cu" signal "IN1")
		(8 "In3.Cu" signal "GND1")
		(10 "In4.Cu" signal "IN2")
		(12 "In5.Cu" signal "GND2")
		(14 "In6.Cu" signal "IN3")
		(16 "In7.Cu" signal "GND3")
		(18 "In8.Cu" signal "VCC")
		(20 "In9.Cu" signal "VCC1")
		(22 "In10.Cu" signal "GND4")
		(24 "In11.Cu" signal "IN4")
		(26 "In12.Cu" signal "GND5")
		(28 "In13.Cu" signal "IN5")
		(30 "In14.Cu" signal "GND6")
		(32 "In15.Cu" signal "IN6")
		(34 "In16.Cu" signal "GND7")
		(2 "B.Cu" signal "BOTTOM")
		(9 "F.Adhes" user "F.Adhesive")
		(11 "B.Adhes" user "B.Adhesive")
		(13 "F.Paste" user "Package Geometry/Pastemask Top")
		(15 "B.Paste" user "Package Geometry/Pastemask Bottom")
		(5 "F.SilkS" user "Ref Des/Silkscreen Top")
		(7 "B.SilkS" user "Ref Des/Silkscreen Bottom")
		(1 "F.Mask" user "Board Geometry/Soldermask Top")
		(3 "B.Mask" user "Board Geometry/Soldermask Bottom")
		(17 "Dwgs.User" user "User.Drawings")
		(19 "Cmts.User" user "User.Comments")
		(21 "Eco1.User" user "User.Eco1")
		(23 "Eco2.User" user "User.Eco2")
		(25 "Edge.Cuts" user "Board Geometry/Outline")
		(27 "Margin" user)
		(31 "F.CrtYd" user "Package Geometry/Place Bound Top")
		(29 "B.CrtYd" user "Package Geometry/Place Bound Bottom")
		(35 "F.Fab" user "Ref Des/Assembly Top")
		(33 "B.Fab" user "Ref Des/Assembly Bottom")
	)
	(footprint ""
		(layer "B.Cu")
		(at 485.20985 -142.805658 -90)
		(property "Reference" "X8012"
			(at 4.4577 -1.50495 270)
			(unlocked yes)
			(layer "B.SilkS")
			(effects
				(font
					(size 0.7874 0.5842)
					(thickness 0.1524)
				)
				(justify left mirror)
			)
		)
		(property "Value" ""
			(at 0 0 90)
			(layer "B.Fab")
			(effects
				(font
					(size 1.27 1.27)
				)
				(justify mirror)
			)
		)
		(property "Device Type" "TP_TDR_4P_FTS_TH-TP_TDR_4P_DIP,EMPTY,TP15"
			(at -1.30175 1.27 180)
			(unlocked yes)
			(layer "B.Fab")
			(hide yes)
			(effects
				(font
					(size 0.635 0.4064)
					(thickness 0.1524)
				)
				(justify mirror)
			)
		)
		(property "User Part Number" "N_A"
			(at -1.30175 1.27 180)
			(unlocked yes)
			(layer "Cmts.User")
			(hide yes)
			(effects
				(font
					(size 0.635 0.4064)
					(thickness 0.1524)
				)
				(justify mirror)
			)
		)
		(duplicate_pad_numbers_are_jumpers no)
		(fp_line
			(start -2.54 3.81)
			(end -2.54 3.6703)
			(stroke
				(width 0.1524)
				(type default)
			)
			(layer "B.SilkS")
		)
		(fp_line
			(start 0 3.81)
			(end -2.54 3.81)
			(stroke
				(width 0.1524)
				(type default)
			)
			(layer "B.SilkS")
		)
		(fp_line
			(start 0 3.175)
			(end 0 3.81)
			(stroke
				(width 0.1524)
				(type default)
			)
			(layer "B.SilkS")
		)
		(fp_line
			(start -2.54 1.4097)
			(end -2.54 1.1303)
			(stroke
				(width 0.1524)
				(type default)
			)
			(layer "B.SilkS")
		)
		(fp_line
			(start 0 0.635)
			(end 0 1.905)
			(stroke
				(width 0.1524)
				(type default)
			)
			(layer "B.SilkS")
		)
		(fp_line
			(start -2.54 -1.1303)
			(end -2.54 -1.27)
			(stroke
				(width 0.1524)
				(type default)
			)
			(layer "B.SilkS")
		)
		(fp_line
			(start -2.54 -1.27)
			(end 0 -1.27)
			(stroke
				(width 0.1524)
				(type default)
			)
			(layer "B.SilkS")
		)
		(fp_line
			(start 0 -1.27)
			(end 0 -0.635)
			(stroke
				(width 0.1524)
				(type default)
			)
			(layer "B.SilkS")
		)
		(fp_poly
			(pts
				(xy 0.761746 0) (xy 2.285746 -0.762) (xy 2.285746 0.762)
			)
			(stroke
				(width 0)
				(type default)
			)
			(fill yes)
			(layer "B.SilkS")
		)
		(fp_line
			(start -2.54 3.81)
			(end -2.54 -1.27)
			(stroke
				(width 0.1)
				(type default)
			)
			(layer "B.Fab")
		)
		(fp_line
			(start 0 3.81)
			(end -2.54 3.81)
			(stroke
				(width 0.1)
				(type default)
			)
			(layer "B.Fab")
		)
		(fp_line
			(start -2.54 -1.27)
			(end 0 -1.27)
			(stroke
				(width 0.1)
				(type default)
			)
			(layer "B.Fab")
		)
		(fp_line
			(start 0 -1.27)
			(end 0 3.81)
			(stroke
				(width 0.1)
				(type default)
			)
			(layer "B.Fab")
		)
		(fp_poly
			(pts
				(xy 0.761746 0) (xy 2.285746 -0.762) (xy 2.285746 0.762)
			)
			(stroke
				(width 0)
				(type default)
			)
			(fill yes)
			(layer "B.Fab")
		)
		(pad "1" thru_hole circle
			(at 0 0 90)
			(size 1.0033 1.0033)
			(drill 0.249936)
			(layers "*.Cu" "*.Mask")
			(remove_unused_layers no)
			(net "TDR_DIFF_85_BOT_DN")
			(clearance 0.10795)
			(padstack
				(mode front_inner_back)
				(layer "Inner"
					(shape circle)
					(size 0.8001 0.8001)
					(clearance 0.1524)
				)
				(layer "B.Cu"
					(shape circle)
					(size 1.0033 1.0033)
					(thermal_gap 0.10795)
					(clearance 0.10795)
				)
			)
		)
		(pad "2" thru_hole circle
			(at -2.54 0 90)
			(size 1.9939 1.9939)
			(drill 0.249936)
			(layers "*.Cu" "*.Mask")
			(remove_unused_layers no)
			(net "T1_GND")
			(clearance 0.10795)
			(padstack
				(mode front_inner_back)
				(layer "Inner"
					(shape circle)
					(size 0.8001 0.8001)
					(clearance 0.1524)
				)
				(layer "B.Cu"
					(shape circle)
					(size 1.9939 1.9939)
					(thermal_gap 0.10795)
					(clearance 0.10795)
				)
			)
		)
		(pad "3" thru_hole circle
			(at -2.54 2.54 90)
			(size 1.9939 1.9939)
			(drill 0.249936)
			(layers "*.Cu" "*.Mask")
			(remove_unused_layers no)
			(net "T1_GND")
			(clearance 0.10795)
			(padstack
				(mode front_inner_back)
				(layer "Inner"
					(shape circle)
					(size 0.8001 0.8001)
					(clearance 0.1524)
				)
				(layer "B.Cu"
					(shape circle)
					(size 1.9939 1.9939)
					(thermal_gap 0.10795)
					(clearance 0.10795)
				)
			)
		)
		(pad "4" thru_hole circle
			(at 0 2.54 90)
			(size 1.0033 1.0033)
			(drill 0.249936)
			(layers "*.Cu" "*.Mask")
			(remove_unused_layers no)
			(net "TDR_DIFF_85_BOT_DP")
			(clearance 0.10795)
			(padstack
				(mode front_inner_back)
				(layer "Inner"
					(shape circle)
					(size 0.8001 0.8001)
					(clearance 0.1524)
				)
				(layer "B.Cu"
					(shape circle)
					(size 1.0033 1.0033)
					(thermal_gap 0.10795)
					(clearance 0.10795)
				)
			)
		)
	)
)
